# T6G (Grand Teton) — schematic netlist excerpt (pin names and nets, part order shuffled) for the footprints in the layout excerpt that follows; sources: Cadence DE-HDL packaged netlist, KiCad conversion of 04192023_DAF0TMB3IC0_F0TG_MB_C_brd_V02_OCP.brd

R266  Q_RES  33 5% CHIP  pkg 0402LF  page 82 : A = FM_CPU1_SA0 ; B = CPU1_SA0
R1237  Q_RES  5.11K 1% CHIP  pkg 0402LF  page 258 : A = P1V8_AUX ; B = P1V8_AUX_ADC

(kicad_pcb
	(version 20260206)
	(generator "pcbnew")
	(generator_version "10.0")
	(general
		(thickness 1.6)
		(legacy_teardrops no)
	)
	(paper "A4")
	(title_block
		(title "04192023_DAF0TMB3IC0_F0TG_MB_C_brd_V02_OCP.brd")
		(comment 1 "Grand Teton / footprints 5412-5414 of 8354")
	)
	(layers
		(0 "F.Cu" signal "TOP")
		(4 "In1.Cu" signal "GND")
		(6 "In2.Cu" signal "IN1")
		(8 "In3.Cu" signal "GND1")
		(10 "In4.Cu" signal "IN2")
		(12 "In5.Cu" signal "GND2")
		(14 "In6.Cu" signal "IN3")
		(16 "In7.Cu" signal "GND3")
		(18 "In8.Cu" signal "VCC")
		(20 "In9.Cu" signal "VCC1")
		(22 "In10.Cu" signal "GND4")
		(24 "In11.Cu" signal "IN4")
		(26 "In12.Cu" signal "GND5")
		(28 "In13.Cu" signal "IN5")
		(30 "In14.Cu" signal "GND6")
		(32 "In15.Cu" signal "IN6")
		(34 "In16.Cu" signal "GND7")
		(2 "B.Cu" signal "BOTTOM")
		(9 "F.Adhes" user "F.Adhesive")
		(11 "B.Adhes" user "B.Adhesive")
		(13 "F.Paste" user "Package Geometry/Pastemask Top")
		(15 "B.Paste" user "Package Geometry/Pastemask Bottom")
		(5 "F.SilkS" user "Ref Des/Silkscreen Top")
		(7 "B.SilkS" user "Ref Des/Silkscreen Bottom")
		(1 "F.Mask" user "Board Geometry/Soldermask Top")
		(3 "B.Mask" user "Board Geometry/Soldermask Bottom")
		(17 "Dwgs.User" user "User.Drawings")
		(19 "Cmts.User" user "User.Comments")
		(21 "Eco1.User" user "User.Eco1")
		(23 "Eco2.User" user "User.Eco2")
		(25 "Edge.Cuts" user "Board Geometry/Outline")
		(27 "Margin" user)
		(31 "F.CrtYd" user "Package Geometry/Place Bound Top")
		(29 "B.CrtYd" user "Package Geometry/Place Bound Bottom")
		(35 "F.Fab" user "Ref Des/Assembly Top")
		(33 "B.Fab" user "Ref Des/Assembly Bottom")
	)
	(footprint ""
		(layer "B.Cu")
		(at 219.61475 -347.604588 180)
		(property "Reference" ""
			(at 0 0 0)
			(layer "B.SilkS")
			(hide yes)
			(effects
				(font
					(size 1.27 1.27)
				)
				(justify mirror)
			)
		)
		(property "Value" ""
			(at 0 0 0)
			(layer "B.Fab")
			(effects
				(font
					(size 1.27 1.27)
				)
				(justify mirror)
			)
		)
		(duplicate_pad_numbers_are_jumpers no)
		(pad "1" smd circle
			(at 0 0)
			(size 0.9906 0.9906)
			(layers "B.Cu" "B.Mask" "B.Paste")
			(net "Net_2232")
		)
		(zone
			(layer "B.Cu")
			(hatch none 0.5)
			(connect_pads
				(clearance 0)
			)
			(min_thickness 0.25)
			(keepout
				(tracks not_allowed)
				(vias allowed)
				(pads allowed)
				(copperpour not_allowed)
				(footprints allowed)
			)
			(placement
				(enabled no)
				(sheetname "")
			)
			(fill
				(thermal_gap 0.5)
				(thermal_bridge_width 0.5)
				(island_removal_mode 0)
			)
			(polygon
				(pts
					(arc
						(start 221.24035 -347.604588)
						(mid 217.98915 -347.604588)
						(end 221.24035 -347.604588)
					)
				)
			)
		)
	)
	(footprint ""
		(layer "B.Cu")
		(at 193.929 -97.119948 90)
		(property "Reference" "R266"
			(at 0 0 90)
			(layer "B.SilkS")
			(hide yes)
			(effects
				(font
					(size 1.27 1.27)
				)
				(justify mirror)
			)
		)
		(property "Value" ""
			(at 0 0 90)
			(layer "B.Fab")
			(effects
				(font
					(size 1.27 1.27)
				)
				(justify mirror)
			)
		)
		(duplicate_pad_numbers_are_jumpers no)
		(fp_line
			(start 0.7874 -0.4064)
			(end -0.7874 -0.4064)
			(stroke
				(width 0.1524)
				(type default)
			)
			(layer "B.SilkS")
		)
		(fp_line
			(start -0.7874 -0.4064)
			(end -0.7874 0.4064)
			(stroke
				(width 0.1524)
				(type default)
			)
			(layer "B.SilkS")
		)
		(fp_line
			(start 0.7874 0.4064)
			(end 0.7874 -0.4064)
			(stroke
				(width 0.1524)
				(type default)
			)
			(layer "B.SilkS")
		)
		(fp_line
			(start -0.7874 0.4064)
			(end 0.7874 0.4064)
			(stroke
				(width 0.1524)
				(type default)
			)
			(layer "B.SilkS")
		)
		(fp_line
			(start 0.67945 -0.305054)
			(end 0.12065 -0.305054)
			(stroke
				(width 0.1)
				(type default)
			)
			(layer "B.Fab")
		)
		(fp_line
			(start 0.12065 -0.305054)
			(end 0.12065 -0.2794)
			(stroke
				(width 0.1)
				(type default)
			)
			(layer "B.Fab")
		)
		(fp_line
			(start -0.12065 -0.3048)
			(end -0.67945 -0.3048)
			(stroke
				(width 0.1)
				(type default)
			)
			(layer "B.Fab")
		)
		(fp_line
			(start -0.67945 -0.3048)
			(end -0.67945 0.3048)
			(stroke
				(width 0.1)
				(type default)
			)
			(layer "B.Fab")
		)
		(fp_line
			(start 0.12065 -0.2794)
			(end -0.12065 -0.2794)
			(stroke
				(width 0.1)
				(type default)
			)
			(layer "B.Fab")
		)
		(fp_line
			(start -0.12065 -0.2794)
			(end -0.12065 -0.3048)
			(stroke
				(width 0.1)
				(type default)
			)
			(layer "B.Fab")
		)
		(fp_line
			(start 0.12065 0.2794)
			(end 0.12065 0.3048)
			(stroke
				(width 0.1)
				(type default)
			)
			(layer "B.Fab")
		)
		(fp_line
			(start -0.120396 0.2794)
			(end 0.12065 0.2794)
			(stroke
				(width 0.1)
				(type default)
			)
			(layer "B.Fab")
		)
		(fp_line
			(start 0.67945 0.3048)
			(end 0.67945 -0.305054)
			(stroke
				(width 0.1)
				(type default)
			)
			(layer "B.Fab")
		)
		(fp_line
			(start 0.12065 0.3048)
			(end 0.67945 0.3048)
			(stroke
				(width 0.1)
				(type default)
			)
			(layer "B.Fab")
		)
		(fp_line
			(start -0.120396 0.3048)
			(end -0.120396 0.2794)
			(stroke
				(width 0.1)
				(type default)
			)
			(layer "B.Fab")
		)
		(fp_line
			(start -0.67945 0.3048)
			(end -0.120396 0.3048)
			(stroke
				(width 0.1)
				(type default)
			)
			(layer "B.Fab")
		)
		(pad "1" smd circle
			(at 0.40005 0 270)
			(size 0 0)
			(layers "B.Cu" "B.Mask" "B.Paste")
			(net "FM_CPU1_SA0")
		)
		(pad "2" smd circle
			(at -0.40005 0 270)
			(size 0 0)
			(layers "B.Cu" "B.Mask" "B.Paste")
			(net "CPU1_SA0")
		)
	)
	(footprint ""
		(layer "B.Cu")
		(at 237.896654 -322.511166)
		(property "Reference" "R1237"
			(at 0 0 0)
			(layer "B.SilkS")
			(hide yes)
			(effects
				(font
					(size 1.27 1.27)
				)
				(justify mirror)
			)
		)
		(property "Value" ""
			(at 0 0 0)
			(layer "B.Fab")
			(effects
				(font
					(size 1.27 1.27)
				)
				(justify mirror)
			)
		)
		(duplicate_pad_numbers_are_jumpers no)
		(fp_line
			(start -0.7874 -0.4064)
			(end -0.7874 0.4064)
			(stroke
				(width 0.1524)
				(type default)
			)
			(layer "B.SilkS")
		)
		(fp_line
			(start -0.7874 0.4064)
			(end 0.7874 0.4064)
			(stroke
				(width 0.1524)
				(type default)
			)
			(layer "B.SilkS")
		)
		(fp_line
			(start 0.7874 -0.4064)
			(end -0.7874 -0.4064)
			(stroke
				(width 0.1524)
				(type default)
			)
			(layer "B.SilkS")
		)
		(fp_line
			(start 0.7874 0.4064)
			(end 0.7874 -0.4064)
			(stroke
				(width 0.1524)
				(type default)
			)
			(layer "B.SilkS")
		)
		(fp_line
			(start -0.67945 -0.3048)
			(end -0.67945 0.3048)
			(stroke
				(width 0.1)
				(type default)
			)
			(layer "B.Fab")
		)
		(fp_line
			(start -0.67945 0.3048)
			(end -0.120396 0.3048)
			(stroke
				(width 0.1)
				(type default)
			)
			(layer "B.Fab")
		)
		(fp_line
			(start -0.12065 -0.3048)
			(end -0.67945 -0.3048)
			(stroke
				(width 0.1)
				(type default)
			)
			(layer "B.Fab")
		)
		(fp_line
			(start -0.12065 -0.2794)
			(end -0.12065 -0.3048)
			(stroke
				(width 0.1)
				(type default)
			)
			(layer "B.Fab")
		)
		(fp_line
			(start -0.120396 0.2794)
			(end 0.12065 0.2794)
			(stroke
				(width 0.1)
				(type default)
			)
			(layer "B.Fab")
		)
		(fp_line
			(start -0.120396 0.3048)
			(end -0.120396 0.2794)
			(stroke
				(width 0.1)
				(type default)
			)
			(layer "B.Fab")
		)
		(fp_line
			(start 0.12065 -0.305054)
			(end 0.12065 -0.2794)
			(stroke
				(width 0.1)
				(type default)
			)
			(layer "B.Fab")
		)
		(fp_line
			(start 0.12065 -0.2794)
			(end -0.12065 -0.2794)
			(stroke
				(width 0.1)
				(type default)
			)
			(layer "B.Fab")
		)
		(fp_line
			(start 0.12065 0.2794)
			(end 0.12065 0.3048)
			(stroke
				(width 0.1)
				(type default)
			)
			(layer "B.Fab")
		)
		(fp_line
			(start 0.12065 0.3048)
			(end 0.67945 0.3048)
			(stroke
				(width 0.1)
				(type default)
			)
			(layer "B.Fab")
		)
		(fp_line
			(start 0.67945 -0.305054)
			(end 0.12065 -0.305054)
			(stroke
				(width 0.1)
				(type default)
			)
			(layer "B.Fab")
		)
		(fp_line
			(start 0.67945 0.3048)
			(end 0.67945 -0.305054)
			(stroke
				(width 0.1)
				(type default)
			)
			(layer "B.Fab")
		)
		(pad "1" smd circle
			(at 0.40005 0 180)
			(size 0 0)
			(layers "B.Cu" "B.Mask" "B.Paste")
			(net "P1V8_AUX")
		)
		(pad "2" smd circle
			(at -0.40005 0 180)
			(size 0 0)
			(layers "B.Cu" "B.Mask" "B.Paste")
			(net "P1V8_AUX_ADC")
		)
	)
)
